(kicad_pcb
	(version 20241229)
	(generator "pcbnew")
	(generator_version "9.0")
	(general
		(thickness 1.61)
		(legacy_teardrops no)
	)
	(paper "A3")
	(title_block
		(title "RDIMM DDR5 Tester")
		(date "2026-05-21")
		(rev "2.2.0")
		(company "Antmicro")
		(comment 9 "footprints 241-244 of 796")
	)
	(layers
		(0 "F.Cu" signal)
		(4 "In1.Cu" power)
		(6 "In2.Cu" mixed)
		(8 "In3.Cu" power)
		(10 "In4.Cu" mixed)
		(12 "In5.Cu" power)
		(14 "In6.Cu" mixed)
		(16 "In7.Cu" power)
		(18 "In8.Cu" power)
		(20 "In9.Cu" mixed)
		(22 "In10.Cu" power)
		(2 "B.Cu" signal)
		(9 "F.Adhes" user "F.Adhesive")
		(11 "B.Adhes" user "B.Adhesive")
		(13 "F.Paste" user)
		(15 "B.Paste" user)
		(5 "F.SilkS" user "F.Silkscreen")
		(7 "B.SilkS" user "B.Silkscreen")
		(1 "F.Mask" user)
		(3 "B.Mask" user)
		(17 "Dwgs.User" user "User.Drawings")
		(19 "Cmts.User" user "User.Comments")
		(21 "Eco1.User" user "User.Eco1")
		(23 "Eco2.User" user "User.Eco2")
		(25 "Edge.Cuts" user)
		(27 "Margin" user)
		(31 "F.CrtYd" user "F.Courtyard")
		(29 "B.CrtYd" user "B.Courtyard")
		(35 "F.Fab" user)
		(33 "B.Fab" user)
	)
	(footprint "antmicro-footprints:R_0402_1005Metric"
		(layer "F.Cu")
		(at 141.024499 183.264 90)
		(descr "Resistor SMD 0402")
		(tags "resistor SMD 0402")
		(property "Reference" "R67"
			(at -1.061 2.375501 90)
			(layer "F.SilkS")
			(effects
				(font
					(size 0.7 0.7)
					(thickness 0.15)
				)
				(justify left bottom)
			)
		)
		(property "Value" "R_330R_0402"
			(at -1.011843 1.772047 90)
			(layer "F.Fab")
			(effects
				(font
					(size 0.7 0.7)
					(thickness 0.15)
				)
				(justify left bottom)
			)
		)
		(property "Datasheet" "https://www.bourns.com/docs/product-datasheets/cr.pdf"
			(at 0 0 90)
			(layer "F.Fab")
			(hide yes)
			(effects
				(font
					(size 1.27 1.27)
					(thickness 0.15)
				)
			)
		)
		(property "Manufacturer" "Bourns"
			(at 0 0 90)
			(unlocked yes)
			(layer "F.Fab")
			(hide yes)
			(effects
				(font
					(size 1 1)
					(thickness 0.15)
				)
			)
		)
		(property "MPN" "CR0402-FX-3300GLF"
			(at 0 0 90)
			(unlocked yes)
			(layer "F.Fab")
			(hide yes)
			(effects
				(font
					(size 1 1)
					(thickness 0.15)
				)
			)
		)
		(property "Val" "330R"
			(at 0 0 90)
			(unlocked yes)
			(layer "F.Fab")
			(hide yes)
			(effects
				(font
					(size 1 1)
					(thickness 0.15)
				)
			)
		)
		(property "License" "Apache-2.0"
			(at 0 0 90)
			(unlocked yes)
			(layer "F.Fab")
			(hide yes)
			(effects
				(font
					(size 1 1)
					(thickness 0.15)
				)
			)
		)
		(property "Author" "Antmicro"
			(at 0 0 90)
			(unlocked yes)
			(layer "F.Fab")
			(hide yes)
			(effects
				(font
					(size 1 1)
					(thickness 0.15)
				)
			)
		)
		(property "Tolerance" "1%"
			(at 0 0 90)
			(unlocked yes)
			(layer "F.Fab")
			(hide yes)
			(effects
				(font
					(size 1 1)
					(thickness 0.15)
				)
			)
		)
		(sheetname "/Debug FTDI + VNA/")
		(sheetfile "debug-ftdi.kicad_sch")
		(attr smd)
		(fp_rect
			(start -0.925 -0.47)
			(end 0.925 0.47)
			(stroke
				(width 0.05)
				(type default)
			)
			(fill no)
			(layer "F.CrtYd")
		)
		(fp_rect
			(start -0.5 -0.25)
			(end 0.5 0.25)
			(stroke
				(width 0.15)
				(type solid)
			)
			(fill no)
			(layer "F.Fab")
		)
		(fp_text user "Author: Antmicro"
			(at -0.95 4.169 90)
			(layer "F.Fab")
			(effects
				(font
					(size 0.7 0.7)
					(thickness 0.15)
				)
				(justify left bottom)
			)
		)
		(fp_text user "License: Apache-2.0"
			(at -0.95 5.169 90)
			(layer "F.Fab")
			(effects
				(font
					(size 0.7 0.7)
					(thickness 0.15)
				)
				(justify left bottom)
			)
		)
		(fp_text user "${REFERENCE}"
			(at -0.95 3.168 90)
			(layer "F.Fab")
			(effects
				(font
					(size 0.7 0.7)
					(thickness 0.15)
				)
				(justify left bottom)
			)
		)
		(pad "1" smd roundrect
			(at -0.48 0 90)
			(size 0.59 0.64)
			(layers "F.Cu" "F.Mask" "F.Paste")
			(roundrect_rratio 0.25)
			(net 43 "Net-(D13-A)")
			(pintype "passive")
		)
		(pad "2" smd roundrect
			(at 0.48 0 90)
			(size 0.59 0.64)
			(layers "F.Cu" "F.Mask" "F.Paste")
			(roundrect_rratio 0.25)
			(net 446 "/Debug FTDI + VNA/LED_RX1")
			(pintype "passive")
		)
	)
	(footprint "antmicro-footprints:LED_0402_1005Metric_G"
		(layer "F.Cu")
		(at 243.051 116.4)
		(property "Reference" "D21"
			(at 0 -0.6 0)
			(unlocked yes)
			(layer "F.SilkS")
			(hide yes)
			(effects
				(font
					(size 0.7 0.7)
					(thickness 0.15)
				)
				(justify left bottom)
			)
		)
		(property "Value" "LED_G_0402_VLMTG1500-GS08"
			(at 0 1.5 0)
			(unlocked yes)
			(layer "F.Fab")
			(effects
				(font
					(size 0.7 0.7)
					(thickness 0.15)
				)
				(justify left bottom)
			)
		)
		(property "Datasheet" "https://www.vishay.com/docs/82554/vlmo1500.pdf"
			(at 0 0 0)
			(layer "F.Fab")
			(hide yes)
			(effects
				(font
					(size 1.27 1.27)
					(thickness 0.15)
				)
			)
		)
		(property "MPN" "VLMTG1500-GS08"
			(at 0 0 0)
			(unlocked yes)
			(layer "F.Fab")
			(hide yes)
			(effects
				(font
					(size 1 1)
					(thickness 0.15)
				)
			)
		)
		(property "Manufacturer" "Vishay"
			(at 0 0 0)
			(unlocked yes)
			(layer "F.Fab")
			(hide yes)
			(effects
				(font
					(size 1 1)
					(thickness 0.15)
				)
			)
		)
		(property "Color" "Green"
			(at 0 0 0)
			(unlocked yes)
			(layer "F.Fab")
			(hide yes)
			(effects
				(font
					(size 1 1)
					(thickness 0.15)
				)
			)
		)
		(property "Author" "Antmicro"
			(at 0 0 0)
			(unlocked yes)
			(layer "F.Fab")
			(hide yes)
			(effects
				(font
					(size 1 1)
					(thickness 0.15)
				)
			)
		)
		(property "License" "Apache-2.0"
			(at 0 0 0)
			(unlocked yes)
			(layer "F.Fab")
			(hide yes)
			(effects
				(font
					(size 1 1)
					(thickness 0.15)
				)
			)
		)
		(sheetname "/DDR5 RDIMM/")
		(sheetfile "ddr5-rdimm.kicad_sch")
		(attr smd)
		(fp_line
			(start -0.9 -0.4)
			(end -0.9 0.4)
			(stroke
				(width 0.15)
				(type solid)
			)
			(layer "F.SilkS")
		)
		(fp_line
			(start -0.175 -0.4)
			(end 0.175 -0.4)
			(stroke
				(width 0.15)
				(type solid)
			)
			(layer "F.SilkS")
		)
		(fp_line
			(start -0.175 0.4)
			(end 0.175 0.4)
			(stroke
				(width 0.15)
				(type solid)
			)
			(layer "F.SilkS")
		)
		(fp_rect
			(start -0.925 -0.47)
			(end 0.925 0.47)
			(stroke
				(width 0.05)
				(type default)
			)
			(fill no)
			(layer "F.CrtYd")
		)
		(fp_line
			(start -0.489 -0.248)
			(end -0.489 0.26)
			(stroke
				(width 0.15)
				(type solid)
			)
			(layer "F.Fab")
		)
		(fp_line
			(start -0.489 -0.248)
			(end -0.489 0.26)
			(stroke
				(width 0.15)
				(type solid)
			)
			(layer "F.Fab")
		)
		(fp_line
			(start -0.489 0.26)
			(end -0.158 0.26)
			(stroke
				(width 0.15)
				(type solid)
			)
			(layer "F.Fab")
		)
		(fp_line
			(start -0.489 0.26)
			(end 0.501 0.26)
			(stroke
				(width 0.15)
				(type solid)
			)
			(layer "F.Fab")
		)
		(fp_line
			(start -0.173 -0.202)
			(end -0.173 0.102)
			(stroke
				(width 0.15)
				(type solid)
			)
			(layer "F.Fab")
		)
		(fp_line
			(start -0.173 0.202)
			(end -0.173 0.102)
			(stroke
				(width 0.15)
				(type solid)
			)
			(layer "F.Fab")
		)
		(fp_line
			(start -0.158 -0.248)
			(end -0.489 -0.248)
			(stroke
				(width 0.15)
				(type solid)
			)
			(layer "F.Fab")
		)
		(fp_line
			(start -0.158 0.26)
			(end -0.158 -0.248)
			(stroke
				(width 0.15)
				(type solid)
			)
			(layer "F.Fab")
		)
		(fp_line
			(start -0.074 0)
			(end 0.228 0.202)
			(stroke
				(width 0.15)
				(type solid)
			)
			(layer "F.Fab")
		)
		(fp_line
			(start 0.172 -0.248)
			(end 0.172 0.26)
			(stroke
				(width 0.15)
				(type solid)
			)
			(layer "F.Fab")
		)
		(fp_line
			(start 0.172 0.26)
			(end 0.501 0.26)
			(stroke
				(width 0.15)
				(type solid)
			)
			(layer "F.Fab")
		)
		(fp_line
			(start 0.228 -0.202)
			(end -0.074 0)
			(stroke
				(width 0.15)
				(type solid)
			)
			(layer "F.Fab")
		)
		(fp_line
			(start 0.228 0)
			(end 0.228 -0.202)
			(stroke
				(width 0.15)
				(type solid)
			)
			(layer "F.Fab")
		)
		(fp_line
			(start 0.228 0.202)
			(end 0.228 0)
			(stroke
				(width 0.15)
				(type solid)
			)
			(layer "F.Fab")
		)
		(fp_line
			(start 0.501 -0.248)
			(end -0.489 -0.248)
			(stroke
				(width 0.15)
				(type solid)
			)
			(layer "F.Fab")
		)
		(fp_line
			(start 0.501 -0.248)
			(end 0.172 -0.248)
			(stroke
				(width 0.15)
				(type solid)
			)
			(layer "F.Fab")
		)
		(fp_line
			(start 0.501 0.26)
			(end 0.501 -0.248)
			(stroke
				(width 0.15)
				(type solid)
			)
			(layer "F.Fab")
		)
		(fp_line
			(start 0.501 0.26)
			(end 0.501 -0.248)
			(stroke
				(width 0.15)
				(type solid)
			)
			(layer "F.Fab")
		)
		(fp_text user "${REFERENCE}"
			(at 0 2.95 0)
			(unlocked yes)
			(layer "F.Fab")
			(effects
				(font
					(size 0.7 0.7)
					(thickness 0.15)
				)
				(justify left bottom)
			)
		)
		(fp_text user "License: Apache-2.0"
			(at 0 5.35 0)
			(layer "F.Fab")
			(effects
				(font
					(size 0.7 0.7)
					(thickness 0.15)
				)
				(justify left bottom)
			)
		)
		(fp_text user "Author: Antmicro"
			(at 0 4.15 0)
			(layer "F.Fab")
			(effects
				(font
					(size 0.7 0.7)
					(thickness 0.15)
				)
				(justify left bottom)
			)
		)
		(pad "1" smd roundrect
			(at -0.48 0)
			(size 0.59 0.64)
			(layers "F.Cu" "F.Mask" "F.Paste")
			(roundrect_rratio 0.25)
			(net 804 "Net-(D21-C)")
			(pinfunction "C")
			(pintype "passive")
		)
		(pad "2" smd roundrect
			(at 0.48 0)
			(size 0.59 0.64)
			(layers "F.Cu" "F.Mask" "F.Paste")
			(roundrect_rratio 0.25)
			(net 802 "/DDR5 RDIMM/VIN_BULK")
			(pinfunction "A")
			(pintype "passive")
		)
	)
	(footprint "antmicro-footprints:R_0402_1005Metric"
		(layer "F.Cu")
		(at 260.52 176.1095 -90)
		(descr "Resistor SMD 0402")
		(tags "resistor SMD 0402")
		(property "Reference" "R165"
			(at 1.9905 -0.38 90)
			(layer "F.SilkS")
			(effects
				(font
					(size 0.7 0.7)
					(thickness 0.15)
				)
				(justify right bottom)
			)
		)
		(property "Value" "R_0R_0402"
			(at -1.011843 1.772047 90)
			(layer "F.Fab")
			(effects
				(font
					(size 0.7 0.7)
					(thickness 0.15)
				)
				(justify right bottom)
			)
		)
		(property "Datasheet" "https://industrial.panasonic.com/cdbs/www-data/pdf/RDA0000/AOA0000C301.pdf"
			(at 0 0 270)
			(layer "F.Fab")
			(hide yes)
			(effects
				(font
					(size 1.27 1.27)
					(thickness 0.15)
				)
			)
		)
		(property "Manufacturer" "Panasonic"
			(at 0 0 270)
			(unlocked yes)
			(layer "F.Fab")
			(hide yes)
			(effects
				(font
					(size 1 1)
					(thickness 0.15)
				)
			)
		)
		(property "MPN" "ERJ2GE0R00X"
			(at 0 0 270)
			(unlocked yes)
			(layer "F.Fab")
			(hide yes)
			(effects
				(font
					(size 1 1)
					(thickness 0.15)
				)
			)
		)
		(property "Val" "0R"
			(at 0 0 270)
			(unlocked yes)
			(layer "F.Fab")
			(hide yes)
			(effects
				(font
					(size 1 1)
					(thickness 0.15)
				)
			)
		)
		(property "License" "Apache-2.0"
			(at 0 0 270)
			(unlocked yes)
			(layer "F.Fab")
			(hide yes)
			(effects
				(font
					(size 1 1)
					(thickness 0.15)
				)
			)
		)
		(property "Author" "Antmicro"
			(at 0 0 270)
			(unlocked yes)
			(layer "F.Fab")
			(hide yes)
			(effects
				(font
					(size 1 1)
					(thickness 0.15)
				)
			)
		)
		(property "Tolerance" "~"
			(at 0 0 270)
			(unlocked yes)
			(layer "F.Fab")
			(hide yes)
			(effects
				(font
					(size 1 1)
					(thickness 0.15)
				)
			)
		)
		(property "Current" "1A"
			(at 0 0 270)
			(unlocked yes)
			(layer "F.Fab")
			(hide yes)
			(effects
				(font
					(size 1 1)
					(thickness 0.15)
				)
			)
		)
		(sheetname "/Supply/DC-DC AUX, MGT/")
		(sheetfile "dc-dc-aux-mgt.kicad_sch")
		(attr smd)
		(fp_rect
			(start -0.925 -0.47)
			(end 0.925 0.47)
			(stroke
				(width 0.05)
				(type default)
			)
			(fill no)
			(layer "F.CrtYd")
		)
		(fp_rect
			(start -0.5 -0.25)
			(end 0.5 0.25)
			(stroke
				(width 0.15)
				(type solid)
			)
			(fill no)
			(layer "F.Fab")
		)
		(fp_text user "${REFERENCE}"
			(at -0.95 3.168 270)
			(layer "F.Fab")
			(effects
				(font
					(size 0.7 0.7)
					(thickness 0.15)
				)
				(justify left bottom)
			)
		)
		(fp_text user "Author: Antmicro"
			(at -0.95 4.169 270)
			(layer "F.Fab")
			(effects
				(font
					(size 0.7 0.7)
					(thickness 0.15)
				)
				(justify left bottom)
			)
		)
		(fp_text user "License: Apache-2.0"
			(at -0.95 5.169 270)
			(layer "F.Fab")
			(effects
				(font
					(size 0.7 0.7)
					(thickness 0.15)
				)
				(justify left bottom)
			)
		)
		(pad "1" smd roundrect
			(at -0.48 0 270)
			(size 0.59 0.64)
			(layers "F.Cu" "F.Mask" "F.Paste")
			(roundrect_rratio 0.25)
			(net 717 "/Supply/DC-DC AUX, MGT/FB4")
			(pintype "passive")
		)
		(pad "2" smd roundrect
			(at 0.48 0 270)
			(size 0.59 0.64)
			(layers "F.Cu" "F.Mask" "F.Paste")
			(roundrect_rratio 0.25)
			(net 225 "/Supply/DC-DC AUX, MGT/MGTAVCCAUX_local")
			(pintype "passive")
		)
	)
	(footprint "antmicro-footprints:SOT-23-6"
		(layer "F.Cu")
		(at 254.139499 140.3 90)
		(property "Reference" "U31"
			(at -0.7 2.960501 90)
			(layer "F.SilkS")
			(effects
				(font
					(size 0.7 0.7)
					(thickness 0.15)
				)
				(justify left bottom)
			)
		)
		(property "Value" "LM3880"
			(at -1.75 2.75 90)
			(layer "F.Fab")
			(effects
				(font
					(size 0.7 0.7)
					(thickness 0.15)
				)
				(justify left bottom)
			)
		)
		(property "Datasheet" "http://www.ti.com/lit/ds/symlink/lm3880.pdf"
			(at 0 0 90)
			(layer "F.Fab")
			(hide yes)
			(effects
				(font
					(size 1.27 1.27)
					(thickness 0.15)
				)
			)
		)
		(property "Manufacturer" "Texas Instruments"
			(at 0 0 90)
			(unlocked yes)
			(layer "F.Fab")
			(hide yes)
			(effects
				(font
					(size 1 1)
					(thickness 0.15)
				)
			)
		)
		(property "MPN" "LM3880MFX-1AA/NOPB"
			(at 0 0 90)
			(unlocked yes)
			(layer "F.Fab")
			(hide yes)
			(effects
				(font
					(size 1 1)
					(thickness 0.15)
				)
			)
		)
		(property "Author" "Antmicro"
			(at 0 0 90)
			(unlocked yes)
			(layer "F.Fab")
			(hide yes)
			(effects
				(font
					(size 1 1)
					(thickness 0.15)
				)
			)
		)
		(property "License" "Apache-2.0"
			(at 0 0 90)
			(unlocked yes)
			(layer "F.Fab")
			(hide yes)
			(effects
				(font
					(size 1 1)
					(thickness 0.15)
				)
			)
		)
		(property ki_fp_filters "SOT?23*")
		(sheetname "/Supply/")
		(sheetfile "supply.kicad_sch")
		(attr smd)
		(fp_line
			(start 1.45 -0.757)
			(end 1.45 -0.457)
			(stroke
				(width 0.12)
				(type solid)
			)
			(layer "F.SilkS")
		)
		(fp_line
			(start 1.3 -0.757)
			(end 1.45 -0.757)
			(stroke
				(width 0.12)
				(type solid)
			)
			(layer "F.SilkS")
		)
		(fp_line
			(start -1.3 -0.757)
			(end -1.45 -0.757)
			(stroke
				(width 0.12)
				(type solid)
			)
			(layer "F.SilkS")
		)
		(fp_line
			(start -1.45 -0.757)
			(end -1.45 -0.457)
			(stroke
				(width 0.12)
				(type solid)
			)
			(layer "F.SilkS")
		)
		(fp_line
			(start 1.45 0.643)
			(end 1.45 0.343)
			(stroke
				(width 0.12)
				(type solid)
			)
			(layer "F.SilkS")
		)
		(fp_line
			(start 1.3 0.643)
			(end 1.45 0.643)
			(stroke
				(width 0.12)
				(type solid)
			)
			(layer "F.SilkS")
		)
		(fp_line
			(start -1.45 0.643)
			(end -1.45 0.343)
			(stroke
				(width 0.12)
				(type solid)
			)
			(layer "F.SilkS")
		)
		(fp_rect
			(start -1.55 -1.85)
			(end 1.55 1.75)
			(stroke
				(width 0.05)
				(type solid)
			)
			(fill no)
			(layer "F.CrtYd")
		)
		(fp_line
			(start 1.5 -0.757)
			(end 1.5 0.643)
			(stroke
				(width 0.1)
				(type solid)
			)
			(layer "F.Fab")
		)
		(fp_line
			(start -1.5 -0.757)
			(end 1.5 -0.757)
			(stroke
				(width 0.1)
				(type solid)
			)
			(layer "F.Fab")
		)
		(fp_line
			(start 1.5 0.643)
			(end -1.5 0.643)
			(stroke
				(width 0.1)
				(type solid)
			)
			(layer "F.Fab")
		)
		(fp_line
			(start -1.5 0.643)
			(end -1.5 -0.757)
			(stroke
				(width 0.1)
				(type solid)
			)
			(layer "F.Fab")
		)
		(fp_text user "."
			(at -1.4 1.2 90)
			(layer "F.SilkS")
			(effects
				(font
					(size 1 1)
					(thickness 0.15)
				)
			)
		)
		(fp_text user "${REFERENCE}"
			(at -1.75 4 90)
			(layer "F.Fab")
			(effects
				(font
					(size 0.7 0.7)
					(thickness 0.15)
				)
				(justify left bottom)
			)
		)
		(fp_text user "Author: Antmicro"
			(at -1.829 5.25 90)
			(layer "F.Fab")
			(effects
				(font
					(size 0.7 0.7)
					(thickness 0.15)
				)
				(justify left bottom)
			)
		)
		(fp_text user "License: Apache-2.0"
			(at -1.75 6.5 90)
			(layer "F.Fab")
			(effects
				(font
					(size 0.7 0.7)
					(thickness 0.15)
				)
				(justify left bottom)
			)
		)
		(pad "1" smd roundrect
			(at -0.954 1.1 90)
			(size 0.55 1)
			(layers "F.Cu" "F.Mask" "F.Paste")
			(roundrect_rratio 0.15)
			(net 38 "+3V3_AON")
			(pinfunction "VCC")
			(pintype "power_in")
		)
		(pad "2" smd roundrect
			(at -0.003 1.1 90)
			(size 0.55 1)
			(layers "F.Cu" "F.Mask" "F.Paste")
			(roundrect_rratio 0.15)
			(net 1 "GND")
			(pinfunction "GND")
			(pintype "power_in")
		)
		(pad "3" smd roundrect
			(at 0.947 1.1 90)
			(size 0.55 1)
			(layers "F.Cu" "F.Mask" "F.Paste")
			(roundrect_rratio 0.15)
			(net 625 "Net-(Q17-D)")
			(pinfunction "EN")
			(pintype "input")
		)
		(pad "4" smd roundrect
			(at 0.947 -1.214 90)
			(size 0.55 1)
			(layers "F.Cu" "F.Mask" "F.Paste")
			(roundrect_rratio 0.15)
			(net 170 "/Supply/EN3")
			(pinfunction "FLAG3")
			(pintype "open_collector")
		)
		(pad "5" smd roundrect
			(at -0.003 -1.214 90)
			(size 0.55 1)
			(layers "F.Cu" "F.Mask" "F.Paste")
			(roundrect_rratio 0.15)
			(net 169 "/Supply/EN2")
			(pinfunction "FLAG2")
			(pintype "open_collector")
		)
		(pad "6" smd roundrect
			(at -0.954 -1.214 90)
			(size 0.55 1)
			(layers "F.Cu" "F.Mask" "F.Paste")
			(roundrect_rratio 0.15)
			(net 168 "/Supply/EN1")
			(pinfunction "FLAG1")
			(pintype "open_collector")
		)
	)
)
